(kicad_pcb
	(version 20241229)
	(generator "pcbnew")
	(generator_version "9.0")
	(general
		(thickness 1.711)
		(legacy_teardrops no)
	)
	(paper "A4")
	(title_block
		(title "Antmicro Baseboard for Jetson AGX Thor")
		(date "2026-02-18")
		(rev "1.1.0")
		(company "Antmicro Ltd")
		(comment 1 "www.antmicro.com")
		(comment 9 "footprint 710 of 1170 (J18), pads 1-95 of 564")
	)
	(layers
		(0 "F.Cu" signal)
		(4 "In1.Cu" signal)
		(6 "In2.Cu" signal)
		(8 "In3.Cu" signal)
		(10 "In4.Cu" jumper)
		(12 "In5.Cu" signal)
		(14 "In6.Cu" signal)
		(16 "In7.Cu" signal)
		(18 "In8.Cu" signal)
		(2 "B.Cu" signal)
		(9 "F.Adhes" user "F.Adhesive")
		(11 "B.Adhes" user "B.Adhesive")
		(13 "F.Paste" user)
		(15 "B.Paste" user)
		(5 "F.SilkS" user "F.Silkscreen")
		(7 "B.SilkS" user "B.Silkscreen")
		(1 "F.Mask" user)
		(3 "B.Mask" user)
		(17 "Dwgs.User" user "User.Drawings")
		(19 "Cmts.User" user "User.Comments")
		(21 "Eco1.User" user "User.Eco1")
		(23 "Eco2.User" user "User.Eco2")
		(25 "Edge.Cuts" user)
		(27 "Margin" user)
		(31 "F.CrtYd" user "F.Courtyard")
		(29 "B.CrtYd" user "B.Courtyard")
		(35 "F.Fab" user)
		(33 "B.Fab" user)
	)
	(footprint "antmicro-footprints:ASP-208571-01_mounting_holes"
		(locked yes)
		(layer "B.Cu")
		(at 77.680532 103.71 90)
		(property "Reference" "J18"
			(at -25.89 11.119468 270)
			(layer "B.SilkS")
			(effects
				(font
					(size 0.7 0.7)
					(thickness 0.15)
				)
				(justify left bottom mirror)
			)
		)
		(property "Value" "ASP-208571-01_mounting_holes"
			(at -15.05 -10.885 270)
			(layer "B.Fab")
			(effects
				(font
					(size 0.7 0.7)
					(thickness 0.15)
				)
				(justify left bottom mirror)
			)
		)
		(property "Datasheet" "https://suddendocs.samtec.com/prints/asp-208571-01-mkt.pdf"
			(at 0 0 270)
			(layer "B.Fab")
			(hide yes)
			(effects
				(font
					(size 1.27 1.27)
					(thickness 0.15)
				)
				(justify mirror)
			)
		)
		(property "Description" "FMC connector"
			(at 0 0 270)
			(layer "B.Fab")
			(hide yes)
			(effects
				(font
					(size 1.27 1.27)
					(thickness 0.15)
				)
				(justify mirror)
			)
		)
		(property "MPN" "ASP-208571-01"
			(at 0 0 90)
			(unlocked yes)
			(layer "B.Fab")
			(hide yes)
			(effects
				(font
					(size 1 1)
					(thickness 0.15)
				)
				(justify mirror)
			)
		)
		(property "Manufacturer" "Samtec"
			(at 0 0 90)
			(unlocked yes)
			(layer "B.Fab")
			(hide yes)
			(effects
				(font
					(size 1 1)
					(thickness 0.15)
				)
				(justify mirror)
			)
		)
		(property "Author" "Antmicro"
			(at 0 0 90)
			(unlocked yes)
			(layer "B.Fab")
			(hide yes)
			(effects
				(font
					(size 1 1)
					(thickness 0.15)
				)
				(justify mirror)
			)
		)
		(property "License" "Apache-2.0"
			(at 0 0 90)
			(unlocked yes)
			(layer "B.Fab")
			(hide yes)
			(effects
				(font
					(size 1 1)
					(thickness 0.15)
				)
				(justify mirror)
			)
		)
		(sheetname "/Expansion connector/")
		(sheetfile "expansion_connector.kicad_sch")
		(attr smd)
		(pad "" np_thru_hole circle
			(at -31.5 -1.88 90)
			(size 6 6)
			(drill 3.2)
			(layers "*.Cu" "*.Mask")
		)
		(pad "" np_thru_hole circle
			(at -27.19 -3.05 90)
			(size 1.27 1.27)
			(drill 1.27)
			(layers "*.Cu" "*.Mask")
		)
		(pad "" np_thru_hole circle
			(at 27.19 0 90)
			(size 1.27 1.27)
			(drill 1.27)
			(layers "*.Cu" "*.Mask")
		)
		(pad "" np_thru_hole circle
			(at 31.5 -1.84 90)
			(size 6 6)
			(drill 3.2)
			(layers "*.Cu" "*.Mask")
		)
		(pad "A01" smd circle
			(at 24.765 5.715 90)
			(size 0.64 0.64)
			(layers "B.Cu" "B.Mask")
			(net 1 "GND")
			(pinfunction "A01")
			(pintype "passive")
		)
		(pad "A02" smd circle
			(at 23.495 5.715 90)
			(size 0.64 0.64)
			(layers "B.Cu" "B.Mask")
			(net 656 "/Expansion connector/DP2.AUX-")
			(pinfunction "A02")
			(pintype "passive")
		)
		(pad "A03" smd circle
			(at 22.225 5.715 90)
			(size 0.64 0.64)
			(layers "B.Cu" "B.Mask")
			(net 572 "/Expansion connector/DP2.AUX+")
			(pinfunction "A03")
			(pintype "passive")
		)
		(pad "A04" smd circle
			(at 20.955 5.715 90)
			(size 0.64 0.64)
			(layers "B.Cu" "B.Mask")
			(net 1 "GND")
			(pinfunction "A04")
			(pintype "passive")
		)
		(pad "A05" smd circle
			(at 19.685 5.715 90)
			(size 0.64 0.64)
			(layers "B.Cu" "B.Mask")
			(net 1 "GND")
			(pinfunction "A05")
			(pintype "passive")
		)
		(pad "A06" smd circle
			(at 18.415 5.715 90)
			(size 0.64 0.64)
			(layers "B.Cu" "B.Mask")
			(net 737 "/Expansion connector/DP2.TX0-")
			(pinfunction "A06")
			(pintype "passive")
		)
		(pad "A07" smd circle
			(at 17.145 5.715 90)
			(size 0.64 0.64)
			(layers "B.Cu" "B.Mask")
			(net 591 "/Expansion connector/DP2.TX0+")
			(pinfunction "A07")
			(pintype "passive")
		)
		(pad "A08" smd circle
			(at 15.875 5.715 90)
			(size 0.64 0.64)
			(layers "B.Cu" "B.Mask")
			(net 1 "GND")
			(pinfunction "A08")
			(pintype "passive")
		)
		(pad "A09" smd circle
			(at 14.605 5.715 90)
			(size 0.64 0.64)
			(layers "B.Cu" "B.Mask")
			(net 1 "GND")
			(pinfunction "A09")
			(pintype "passive")
		)
		(pad "A10" smd circle
			(at 13.335 5.715 90)
			(size 0.64 0.64)
			(layers "B.Cu" "B.Mask")
			(net 744 "/Expansion connector/DP2.TX1-")
			(pinfunction "A10")
			(pintype "passive")
		)
		(pad "A11" smd circle
			(at 12.065 5.715 90)
			(size 0.64 0.64)
			(layers "B.Cu" "B.Mask")
			(net 726 "/Expansion connector/DP2.TX1+")
			(pinfunction "A11")
			(pintype "passive")
		)
		(pad "A12" smd circle
			(at 10.795 5.715 90)
			(size 0.64 0.64)
			(layers "B.Cu" "B.Mask")
			(net 1 "GND")
			(pinfunction "A12")
			(pintype "passive")
		)
		(pad "A13" smd circle
			(at 9.525 5.715 90)
			(size 0.64 0.64)
			(layers "B.Cu" "B.Mask")
			(net 1 "GND")
			(pinfunction "A13")
			(pintype "passive")
		)
		(pad "A14" smd circle
			(at 8.255 5.715 90)
			(size 0.64 0.64)
			(layers "B.Cu" "B.Mask")
			(net 742 "/Expansion connector/DP2.TX2-")
			(pinfunction "A14")
			(pintype "passive")
		)
		(pad "A15" smd circle
			(at 6.985 5.715 90)
			(size 0.64 0.64)
			(layers "B.Cu" "B.Mask")
			(net 756 "/Expansion connector/DP2.TX2+")
			(pinfunction "A15")
			(pintype "passive")
		)
		(pad "A16" smd circle
			(at 5.715 5.715 90)
			(size 0.64 0.64)
			(layers "B.Cu" "B.Mask")
			(net 1 "GND")
			(pinfunction "A16")
			(pintype "passive")
		)
		(pad "A17" smd circle
			(at 4.445 5.715 90)
			(size 0.64 0.64)
			(layers "B.Cu" "B.Mask")
			(net 1 "GND")
			(pinfunction "A17")
			(pintype "passive")
		)
		(pad "A18" smd circle
			(at 3.175 5.715 90)
			(size 0.64 0.64)
			(layers "B.Cu" "B.Mask")
			(net 631 "/Expansion connector/DP2.TX3-")
			(pinfunction "A18")
			(pintype "passive")
		)
		(pad "A19" smd circle
			(at 1.905 5.715 90)
			(size 0.64 0.64)
			(layers "B.Cu" "B.Mask")
			(net 640 "/Expansion connector/DP2.TX3+")
			(pinfunction "A19")
			(pintype "passive")
		)
		(pad "A20" smd circle
			(at 0.635 5.715 90)
			(size 0.64 0.64)
			(layers "B.Cu" "B.Mask")
			(net 1 "GND")
			(pinfunction "A20")
			(pintype "passive")
		)
		(pad "A21" smd circle
			(at -0.635 5.715 90)
			(size 0.64 0.64)
			(layers "B.Cu" "B.Mask")
			(net 1 "GND")
			(pinfunction "A21")
			(pintype "passive")
		)
		(pad "A22" smd circle
			(at -1.905 5.715 90)
			(size 0.64 0.64)
			(layers "B.Cu" "B.Mask")
			(net 482 "unconnected-(J18-PadA22)")
			(pinfunction "A22")
			(pintype "passive+no_connect")
		)
		(pad "A23" smd circle
			(at -3.175 5.715 90)
			(size 0.64 0.64)
			(layers "B.Cu" "B.Mask")
			(net 483 "unconnected-(J18-PadA23)")
			(pinfunction "A23")
			(pintype "passive+no_connect")
		)
		(pad "A24" smd circle
			(at -4.445 5.715 90)
			(size 0.64 0.64)
			(layers "B.Cu" "B.Mask")
			(net 1 "GND")
			(pinfunction "A24")
			(pintype "passive")
		)
		(pad "A25" smd circle
			(at -5.715 5.715 90)
			(size 0.64 0.64)
			(layers "B.Cu" "B.Mask")
			(net 1 "GND")
			(pinfunction "A25")
			(pintype "passive")
		)
		(pad "A26" smd circle
			(at -6.985 5.715 90)
			(size 0.64 0.64)
			(layers "B.Cu" "B.Mask")
			(net 375 "unconnected-(J18-PadA26)")
			(pinfunction "A26")
			(pintype "passive+no_connect")
		)
		(pad "A27" smd circle
			(at -8.255 5.715 90)
			(size 0.64 0.64)
			(layers "B.Cu" "B.Mask")
			(net 590 "unconnected-(J18-PadA27)")
			(pinfunction "A27")
			(pintype "passive+no_connect")
		)
		(pad "A28" smd circle
			(at -9.525 5.715 90)
			(size 0.64 0.64)
			(layers "B.Cu" "B.Mask")
			(net 1 "GND")
			(pinfunction "A28")
			(pintype "passive")
		)
		(pad "A29" smd circle
			(at -10.795 5.715 90)
			(size 0.64 0.64)
			(layers "B.Cu" "B.Mask")
			(net 1 "GND")
			(pinfunction "A29")
			(pintype "passive")
		)
		(pad "A30" smd circle
			(at -12.065 5.715 90)
			(size 0.64 0.64)
			(layers "B.Cu" "B.Mask")
			(net 480 "unconnected-(J18-PadA30)")
			(pinfunction "A30")
			(pintype "passive+no_connect")
		)
		(pad "A31" smd circle
			(at -13.335 5.715 90)
			(size 0.64 0.64)
			(layers "B.Cu" "B.Mask")
			(net 719 "unconnected-(J18-PadA31)")
			(pinfunction "A31")
			(pintype "passive+no_connect")
		)
		(pad "A32" smd circle
			(at -14.605 5.715 90)
			(size 0.64 0.64)
			(layers "B.Cu" "B.Mask")
			(net 1 "GND")
			(pinfunction "A32")
			(pintype "passive")
		)
		(pad "A33" smd circle
			(at -15.875 5.715 90)
			(size 0.64 0.64)
			(layers "B.Cu" "B.Mask")
			(net 1 "GND")
			(pinfunction "A33")
			(pintype "passive")
		)
		(pad "A34" smd circle
			(at -17.145 5.715 90)
			(size 0.64 0.64)
			(layers "B.Cu" "B.Mask")
			(net 599 "unconnected-(J18-PadA34)")
			(pinfunction "A34")
			(pintype "passive+no_connect")
		)
		(pad "A35" smd circle
			(at -18.415 5.715 90)
			(size 0.64 0.64)
			(layers "B.Cu" "B.Mask")
			(net 349 "unconnected-(J18-PadA35)")
			(pinfunction "A35")
			(pintype "passive+no_connect")
		)
		(pad "A36" smd circle
			(at -19.685 5.715 90)
			(size 0.64 0.64)
			(layers "B.Cu" "B.Mask")
			(net 1 "GND")
			(pinfunction "A36")
			(pintype "passive")
		)
		(pad "A37" smd circle
			(at -20.955 5.715 90)
			(size 0.64 0.64)
			(layers "B.Cu" "B.Mask")
			(net 1 "GND")
			(pinfunction "A37")
			(pintype "passive")
		)
		(pad "A38" smd circle
			(at -22.225 5.715 90)
			(size 0.64 0.64)
			(layers "B.Cu" "B.Mask")
			(net 685 "unconnected-(J18-PadA38)")
			(pinfunction "A38")
			(pintype "passive+no_connect")
		)
		(pad "A39" smd circle
			(at -23.495 5.715 90)
			(size 0.64 0.64)
			(layers "B.Cu" "B.Mask")
			(net 650 "unconnected-(J18-PadA39)")
			(pinfunction "A39")
			(pintype "passive+no_connect")
		)
		(pad "A40" smd circle
			(at -24.765 5.715 90)
			(size 0.64 0.64)
			(layers "B.Cu" "B.Mask")
			(net 1 "GND")
			(pinfunction "A40")
			(pintype "passive")
		)
		(pad "B01" smd circle
			(at 24.765 4.445 90)
			(size 0.64 0.64)
			(layers "B.Cu" "B.Mask")
			(net 659 "Net-(J18-PadB01)")
			(pinfunction "B01")
			(pintype "passive")
		)
		(pad "B02" smd circle
			(at 23.495 4.445 90)
			(size 0.64 0.64)
			(layers "B.Cu" "B.Mask")
			(net 1 "GND")
			(pinfunction "B02")
			(pintype "passive")
		)
		(pad "B03" smd circle
			(at 22.225 4.445 90)
			(size 0.64 0.64)
			(layers "B.Cu" "B.Mask")
			(net 1 "GND")
			(pinfunction "B03")
			(pintype "passive")
		)
		(pad "B04" smd circle
			(at 20.955 4.445 90)
			(size 0.64 0.64)
			(layers "B.Cu" "B.Mask")
			(net 648 "/Expansion connector/DP3.TX3+")
			(pinfunction "B04")
			(pintype "passive")
		)
		(pad "B05" smd circle
			(at 19.685 4.445 90)
			(size 0.64 0.64)
			(layers "B.Cu" "B.Mask")
			(net 661 "/Expansion connector/DP3.TX3-")
			(pinfunction "B05")
			(pintype "passive")
		)
		(pad "B06" smd circle
			(at 18.415 4.445 90)
			(size 0.64 0.64)
			(layers "B.Cu" "B.Mask")
			(net 1 "GND")
			(pinfunction "B06")
			(pintype "passive")
		)
		(pad "B07" smd circle
			(at 17.145 4.445 90)
			(size 0.64 0.64)
			(layers "B.Cu" "B.Mask")
			(net 1 "GND")
			(pinfunction "B07")
			(pintype "passive")
		)
		(pad "B08" smd circle
			(at 15.875 4.445 90)
			(size 0.64 0.64)
			(layers "B.Cu" "B.Mask")
			(net 593 "/Expansion connector/DP3.TX2+")
			(pinfunction "B08")
			(pintype "passive")
		)
		(pad "B09" smd circle
			(at 14.605 4.445 90)
			(size 0.64 0.64)
			(layers "B.Cu" "B.Mask")
			(net 680 "/Expansion connector/DP3.TX2-")
			(pinfunction "B09")
			(pintype "passive")
		)
		(pad "B10" smd circle
			(at 13.335 4.445 90)
			(size 0.64 0.64)
			(layers "B.Cu" "B.Mask")
			(net 1 "GND")
			(pinfunction "B10")
			(pintype "passive")
		)
		(pad "B11" smd circle
			(at 12.065 4.445 90)
			(size 0.64 0.64)
			(layers "B.Cu" "B.Mask")
			(net 1 "GND")
			(pinfunction "B11")
			(pintype "passive")
		)
		(pad "B12" smd circle
			(at 10.795 4.445 90)
			(size 0.64 0.64)
			(layers "B.Cu" "B.Mask")
			(net 736 "/Expansion connector/DP3.TX1+")
			(pinfunction "B12")
			(pintype "passive")
		)
		(pad "B13" smd circle
			(at 9.525 4.445 90)
			(size 0.64 0.64)
			(layers "B.Cu" "B.Mask")
			(net 675 "/Expansion connector/DP3.TX1-")
			(pinfunction "B13")
			(pintype "passive")
		)
		(pad "B14" smd circle
			(at 8.255 4.445 90)
			(size 0.64 0.64)
			(layers "B.Cu" "B.Mask")
			(net 1 "GND")
			(pinfunction "B14")
			(pintype "passive")
		)
		(pad "B15" smd circle
			(at 6.985 4.445 90)
			(size 0.64 0.64)
			(layers "B.Cu" "B.Mask")
			(net 1 "GND")
			(pinfunction "B15")
			(pintype "passive")
		)
		(pad "B16" smd circle
			(at 5.715 4.445 90)
			(size 0.64 0.64)
			(layers "B.Cu" "B.Mask")
			(net 691 "/Expansion connector/DP3.TX0+")
			(pinfunction "B16")
			(pintype "passive")
		)
		(pad "B17" smd circle
			(at 4.445 4.445 90)
			(size 0.64 0.64)
			(layers "B.Cu" "B.Mask")
			(net 665 "/Expansion connector/DP3.TX0-")
			(pinfunction "B17")
			(pintype "passive")
		)
		(pad "B18" smd circle
			(at 3.175 4.445 90)
			(size 0.64 0.64)
			(layers "B.Cu" "B.Mask")
			(net 1 "GND")
			(pinfunction "B18")
			(pintype "passive")
		)
		(pad "B19" smd circle
			(at 1.905 4.445 90)
			(size 0.64 0.64)
			(layers "B.Cu" "B.Mask")
			(net 1 "GND")
			(pinfunction "B19")
			(pintype "passive")
		)
		(pad "B20" smd circle
			(at 0.635 4.445 90)
			(size 0.64 0.64)
			(layers "B.Cu" "B.Mask")
			(net 776 "/Expansion connector/DP3.AUX+")
			(pinfunction "B20")
			(pintype "passive")
		)
		(pad "B21" smd circle
			(at -0.635 4.445 90)
			(size 0.64 0.64)
			(layers "B.Cu" "B.Mask")
			(net 657 "/Expansion connector/DP3.AUX-")
			(pinfunction "B21")
			(pintype "passive")
		)
		(pad "B22" smd circle
			(at -1.905 4.445 90)
			(size 0.64 0.64)
			(layers "B.Cu" "B.Mask")
			(net 1 "GND")
			(pinfunction "B22")
			(pintype "passive")
		)
		(pad "B23" smd circle
			(at -3.175 4.445 90)
			(size 0.64 0.64)
			(layers "B.Cu" "B.Mask")
			(net 1 "GND")
			(pinfunction "B23")
			(pintype "passive")
		)
		(pad "B24" smd circle
			(at -4.445 4.445 90)
			(size 0.64 0.64)
			(layers "B.Cu" "B.Mask")
			(net 784 "unconnected-(J18-PadB24)")
			(pinfunction "B24")
			(pintype "passive+no_connect")
		)
		(pad "B25" smd circle
			(at -5.715 4.445 90)
			(size 0.64 0.64)
			(layers "B.Cu" "B.Mask")
			(net 841 "unconnected-(J18-PadB25)")
			(pinfunction "B25")
			(pintype "passive+no_connect")
		)
		(pad "B26" smd circle
			(at -6.985 4.445 90)
			(size 0.64 0.64)
			(layers "B.Cu" "B.Mask")
			(net 1 "GND")
			(pinfunction "B26")
			(pintype "passive")
		)
		(pad "B27" smd circle
			(at -8.255 4.445 90)
			(size 0.64 0.64)
			(layers "B.Cu" "B.Mask")
			(net 1 "GND")
			(pinfunction "B27")
			(pintype "passive")
		)
		(pad "B28" smd circle
			(at -9.525 4.445 90)
			(size 0.64 0.64)
			(layers "B.Cu" "B.Mask")
			(net 313 "unconnected-(J18-PadB28)")
			(pinfunction "B28")
			(pintype "passive+no_connect")
		)
		(pad "B29" smd circle
			(at -10.795 4.445 90)
			(size 0.64 0.64)
			(layers "B.Cu" "B.Mask")
			(net 340 "unconnected-(J18-PadB29)")
			(pinfunction "B29")
			(pintype "passive+no_connect")
		)
		(pad "B30" smd circle
			(at -12.065 4.445 90)
			(size 0.64 0.64)
			(layers "B.Cu" "B.Mask")
			(net 1 "GND")
			(pinfunction "B30")
			(pintype "passive")
		)
		(pad "B31" smd circle
			(at -13.335 4.445 90)
			(size 0.64 0.64)
			(layers "B.Cu" "B.Mask")
			(net 1 "GND")
			(pinfunction "B31")
			(pintype "passive")
		)
		(pad "B32" smd circle
			(at -14.605 4.445 90)
			(size 0.64 0.64)
			(layers "B.Cu" "B.Mask")
			(net 443 "unconnected-(J18-PadB32)")
			(pinfunction "B32")
			(pintype "passive+no_connect")
		)
		(pad "B33" smd circle
			(at -15.875 4.445 90)
			(size 0.64 0.64)
			(layers "B.Cu" "B.Mask")
			(net 397 "unconnected-(J18-PadB33)")
			(pinfunction "B33")
			(pintype "passive+no_connect")
		)
		(pad "B34" smd circle
			(at -17.145 4.445 90)
			(size 0.64 0.64)
			(layers "B.Cu" "B.Mask")
			(net 1 "GND")
			(pinfunction "B34")
			(pintype "passive")
		)
		(pad "B35" smd circle
			(at -18.415 4.445 90)
			(size 0.64 0.64)
			(layers "B.Cu" "B.Mask")
			(net 1 "GND")
			(pinfunction "B35")
			(pintype "passive")
		)
		(pad "B36" smd circle
			(at -19.685 4.445 90)
			(size 0.64 0.64)
			(layers "B.Cu" "B.Mask")
			(net 473 "unconnected-(J18-PadB36)")
			(pinfunction "B36")
			(pintype "passive+no_connect")
		)
		(pad "B37" smd circle
			(at -20.955 4.445 90)
			(size 0.64 0.64)
			(layers "B.Cu" "B.Mask")
			(net 422 "unconnected-(J18-PadB37)")
			(pinfunction "B37")
			(pintype "passive+no_connect")
		)
		(pad "B38" smd circle
			(at -22.225 4.445 90)
			(size 0.64 0.64)
			(layers "B.Cu" "B.Mask")
			(net 1 "GND")
			(pinfunction "B38")
			(pintype "passive")
		)
		(pad "B39" smd circle
			(at -23.495 4.445 90)
			(size 0.64 0.64)
			(layers "B.Cu" "B.Mask")
			(net 1 "GND")
			(pinfunction "B39")
			(pintype "passive")
		)
		(pad "B40" smd circle
			(at -24.765 4.445 90)
			(size 0.64 0.64)
			(layers "B.Cu" "B.Mask")
			(net 777 "Net-(J18-PadB40)")
			(pinfunction "B40")
			(pintype "passive")
		)
		(pad "C01" smd circle
			(at 24.765 3.175 90)
			(size 0.64 0.64)
			(layers "B.Cu" "B.Mask")
			(net 1 "GND")
			(pinfunction "C01")
			(pintype "passive")
		)
		(pad "C02" smd circle
			(at 23.495 3.175 90)
			(size 0.64 0.64)
			(layers "B.Cu" "B.Mask")
			(net 428 "unconnected-(J18-PadC02)")
			(pinfunction "C02")
			(pintype "passive+no_connect")
		)
		(pad "C03" smd circle
			(at 22.225 3.175 90)
			(size 0.64 0.64)
			(layers "B.Cu" "B.Mask")
			(net 357 "unconnected-(J18-PadC03)")
			(pinfunction "C03")
			(pintype "passive+no_connect")
		)
		(pad "C04" smd circle
			(at 20.955 3.175 90)
			(size 0.64 0.64)
			(layers "B.Cu" "B.Mask")
			(net 1 "GND")
			(pinfunction "C04")
			(pintype "passive")
		)
		(pad "C05" smd circle
			(at 19.685 3.175 90)
			(size 0.64 0.64)
			(layers "B.Cu" "B.Mask")
			(net 1 "GND")
			(pinfunction "C05")
			(pintype "passive")
		)
		(pad "C06" smd circle
			(at 18.415 3.175 90)
			(size 0.64 0.64)
			(layers "B.Cu" "B.Mask")
			(net 304 "unconnected-(J18-PadC06)")
			(pinfunction "C06")
			(pintype "passive+no_connect")
		)
		(pad "C07" smd circle
			(at 17.145 3.175 90)
			(size 0.64 0.64)
			(layers "B.Cu" "B.Mask")
			(net 412 "unconnected-(J18-PadC07)")
			(pinfunction "C07")
			(pintype "passive+no_connect")
		)
		(pad "C08" smd circle
			(at 15.875 3.175 90)
			(size 0.64 0.64)
			(layers "B.Cu" "B.Mask")
			(net 1 "GND")
			(pinfunction "C08")
			(pintype "passive")
		)
		(pad "C09" smd circle
			(at 14.605 3.175 90)
			(size 0.64 0.64)
			(layers "B.Cu" "B.Mask")
			(net 1 "GND")
			(pinfunction "C09")
			(pintype "passive")
		)
		(pad "C10" smd circle
			(at 13.335 3.175 90)
			(size 0.64 0.64)
			(layers "B.Cu" "B.Mask")
			(net 569 "/Expansion connector/PCIe_{C3x2}.~{RST}")
			(pinfunction "C10")
			(pintype "passive")
		)
		(pad "C11" smd circle
			(at 12.065 3.175 90)
			(size 0.64 0.64)
			(layers "B.Cu" "B.Mask")
			(net 565 "/Expansion connector/PCIe_{C3x2}.~{CLKREQ}")
			(pinfunction "C11")
			(pintype "passive")
		)
	)
)
